(kicad_pcb
	(version 20260206)
	(generator "pcbnew")
	(generator_version "10.0")
	(general
		(thickness 1.6)
		(legacy_teardrops no)
	)
	(paper "A4")
	(title_block
		(title "v2-pdb — ms_pdb_v2.brd")
		(comment 1 "Open CloudServer (Microsoft) / footprints 258-259 of 348")
	)
	(layers
		(0 "F.Cu" signal "TOP")
		(4 "In1.Cu" signal "GND")
		(6 "In2.Cu" signal "IN1")
		(8 "In3.Cu" signal "VCC")
		(10 "In4.Cu" signal "VCC1")
		(12 "In5.Cu" signal "IN2")
		(14 "In6.Cu" signal "GND1")
		(2 "B.Cu" signal "BOTTOM")
		(9 "F.Adhes" user "F.Adhesive")
		(11 "B.Adhes" user "B.Adhesive")
		(13 "F.Paste" user "Package Geometry/Pastemask Top")
		(15 "B.Paste" user "Package Geometry/Pastemask Bottom")
		(5 "F.SilkS" user "Ref Des/Silkscreen Top")
		(7 "B.SilkS" user "Ref Des/Silkscreen Bottom")
		(1 "F.Mask" user "Board Geometry/Soldermask Top")
		(3 "B.Mask" user "Board Geometry/Soldermask Bottom")
		(17 "Dwgs.User" user "User.Drawings")
		(19 "Cmts.User" user "User.Comments")
		(21 "Eco1.User" user "User.Eco1")
		(23 "Eco2.User" user "User.Eco2")
		(25 "Edge.Cuts" user "Board Geometry/Outline")
		(27 "Margin" user)
		(31 "F.CrtYd" user "Package Geometry/Place Bound Top")
		(29 "B.CrtYd" user "Package Geometry/Place Bound Bottom")
		(35 "F.Fab" user "Ref Des/Assembly Top")
		(33 "B.Fab" user "Ref Des/Assembly Bottom")
	)
	(footprint ""
		(layer "F.Cu")
		(at 30.45968 -525.329912)
		(property "Reference" "J6"
			(at 8.641842 9.092438 90)
			(unlocked yes)
			(layer "F.SilkS")
			(effects
				(font
					(size 0.7874 0.5842)
					(thickness 0.1524)
				)
				(justify left)
			)
		)
		(property "Value" ""
			(at 0 0 0)
			(layer "F.Fab")
			(effects
				(font
					(size 1.27 1.27)
				)
			)
		)
		(duplicate_pad_numbers_are_jumpers no)
		(fp_line
			(start -2.135124 -4.560062)
			(end -2.135124 83.300062)
			(stroke
				(width 0.1524)
				(type default)
			)
			(layer "F.SilkS")
		)
		(fp_line
			(start -2.135124 83.300062)
			(end 7.215124 83.300062)
			(stroke
				(width 0.1524)
				(type default)
			)
			(layer "F.SilkS")
		)
		(fp_line
			(start 7.215124 -4.560062)
			(end -2.135124 -4.560062)
			(stroke
				(width 0.1524)
				(type default)
			)
			(layer "F.SilkS")
		)
		(fp_line
			(start 7.215124 83.300062)
			(end 7.215124 -4.560062)
			(stroke
				(width 0.1524)
				(type default)
			)
			(layer "F.SilkS")
		)
		(fp_poly
			(pts
				(xy -2.491486 0.079248) (xy -5.191506 -0.620776) (xy -5.191506 0.779272)
			)
			(stroke
				(width 0)
				(type default)
			)
			(fill yes)
			(layer "F.SilkS")
		)
		(fp_poly
			(pts
				(xy -2.28219 -0.127) (xy -4.98221 -0.827024) (xy -4.98221 0.573024)
			)
			(stroke
				(width 0)
				(type default)
			)
			(fill yes)
			(layer "B.SilkS")
		)
		(fp_poly
			(pts
				(xy -0.8636 -0.8636) (xy -0.8636 79.6036) (xy -0.8636 79.629) (xy 5.9436 79.629) (xy 5.9436 79.6036)
				(xy 5.9436 -0.8636) (xy 5.9436 -0.889) (xy -0.8636 -0.889)
			)
			(stroke
				(width 0)
				(type default)
			)
			(fill no)
			(layer "B.CrtYd")
		)
		(fp_rect
			(start -2.135124 -4.560062)
			(end 7.21487 83.300062)
			(stroke
				(width 0)
				(type default)
			)
			(fill no)
			(layer "F.CrtYd")
		)
		(fp_line
			(start -2.135124 -4.560062)
			(end 7.215124 -4.560062)
			(stroke
				(width 0.1)
				(type default)
			)
			(layer "F.Fab")
		)
		(fp_line
			(start -2.135124 83.300062)
			(end -2.135124 -4.560062)
			(stroke
				(width 0.1)
				(type default)
			)
			(layer "F.Fab")
		)
		(fp_line
			(start 7.215124 -4.560062)
			(end 7.215124 83.300062)
			(stroke
				(width 0.1)
				(type default)
			)
			(layer "F.Fab")
		)
		(fp_line
			(start 7.215124 83.300062)
			(end -2.135124 83.300062)
			(stroke
				(width 0.1)
				(type default)
			)
			(layer "F.Fab")
		)
		(fp_text user "32"
			(at -4.018788 80.194912 0)
			(unlocked yes)
			(layer "F.SilkS")
			(effects
				(font
					(size 0.7874 0.5842)
					(thickness 0.1524)
				)
				(justify left)
			)
		)
		(fp_text user "1"
			(at -3.120644 -1.027176 0)
			(unlocked yes)
			(layer "F.SilkS")
			(effects
				(font
					(size 0.7874 0.5842)
					(thickness 0.1524)
				)
				(justify left)
			)
		)
		(fp_text user "64"
			(at 7.523988 -0.308864 0)
			(unlocked yes)
			(layer "F.SilkS")
			(effects
				(font
					(size 0.7874 0.5842)
					(thickness 0.1524)
				)
				(justify left)
			)
		)
		(fp_text user "33"
			(at 7.80161 81.392268 0)
			(unlocked yes)
			(layer "F.SilkS")
			(effects
				(font
					(size 0.7874 0.5842)
					(thickness 0.1524)
				)
				(justify left)
			)
		)
		(fp_text user "32"
			(at -1.360678 79.256636 0)
			(unlocked yes)
			(layer "B.SilkS")
			(effects
				(font
					(size 0.7874 0.5842)
					(thickness 0.1524)
				)
				(justify left mirror)
			)
		)
		(fp_text user "1"
			(at -1.297686 -1.511046 0)
			(unlocked yes)
			(layer "B.SilkS")
			(effects
				(font
					(size 0.7874 0.5842)
					(thickness 0.1524)
				)
				(justify left mirror)
			)
		)
		(fp_text user "33"
			(at 5.67055 81.353152 0)
			(unlocked yes)
			(layer "B.SilkS")
			(effects
				(font
					(size 0.7874 0.5842)
					(thickness 0.1524)
				)
				(justify left mirror)
			)
		)
		(fp_text user "64"
			(at 5.908802 -1.856994 0)
			(unlocked yes)
			(layer "B.SilkS")
			(effects
				(font
					(size 0.7874 0.5842)
					(thickness 0.1524)
				)
				(justify left mirror)
			)
		)
		(pad "1" thru_hole rect
			(at 0 0 270)
			(size 1.6256 1.6256)
			(drill 1.1176)
			(layers "*.Cu" "*.Mask")
			(remove_unused_layers no)
			(net "P12V")
			(clearance 0)
			(padstack
				(mode front_inner_back)
				(layer "Inner"
					(shape circle)
					(size 1.6256 1.6256)
					(clearance 0)
				)
				(layer "B.Cu"
					(shape rect)
					(size 1.6256 1.6256)
					(clearance 0)
				)
			)
		)
		(pad "2" thru_hole circle
			(at 0 2.54 270)
			(size 1.6256 1.6256)
			(drill 1.1176)
			(layers "*.Cu" "*.Mask")
			(remove_unused_layers no)
			(net "P12V")
			(clearance 0)
		)
		(pad "3" thru_hole circle
			(at 0 5.08 270)
			(size 1.6256 1.6256)
			(drill 1.1176)
			(layers "*.Cu" "*.Mask")
			(remove_unused_layers no)
			(net "P12V")
			(clearance 0)
		)
		(pad "4" thru_hole circle
			(at 0 7.62 270)
			(size 1.6256 1.6256)
			(drill 1.1176)
			(layers "*.Cu" "*.Mask")
			(remove_unused_layers no)
			(net "P12V")
			(clearance 0)
		)
		(pad "5" thru_hole circle
			(at 0 10.16 270)
			(size 1.6256 1.6256)
			(drill 1.1176)
			(layers "*.Cu" "*.Mask")
			(remove_unused_layers no)
			(net "P12V")
			(clearance 0)
		)
		(pad "6" thru_hole circle
			(at 0 12.7 270)
			(size 1.6256 1.6256)
			(drill 1.1176)
			(layers "*.Cu" "*.Mask")
			(remove_unused_layers no)
			(net "P12V")
			(clearance 0)
		)
		(pad "7" thru_hole circle
			(at 0 15.24 270)
			(size 1.6256 1.6256)
			(drill 1.1176)
			(layers "*.Cu" "*.Mask")
			(remove_unused_layers no)
			(net "P12V")
			(clearance 0)
		)
		(pad "8" thru_hole circle
			(at 0 17.78 270)
			(size 1.6256 1.6256)
			(drill 1.1176)
			(layers "*.Cu" "*.Mask")
			(remove_unused_layers no)
			(net "P12V")
			(clearance 0)
		)
		(pad "9" thru_hole circle
			(at 0 20.32 270)
			(size 1.6256 1.6256)
			(drill 1.1176)
			(layers "*.Cu" "*.Mask")
			(remove_unused_layers no)
			(net "P12V")
			(clearance 0)
		)
		(pad "10" thru_hole circle
			(at 0 22.86 270)
			(size 1.6256 1.6256)
			(drill 1.1176)
			(layers "*.Cu" "*.Mask")
			(remove_unused_layers no)
			(net "P12V")
			(clearance 0)
		)
		(pad "11" thru_hole circle
			(at 0 25.4 270)
			(size 1.6256 1.6256)
			(drill 1.1176)
			(layers "*.Cu" "*.Mask")
			(remove_unused_layers no)
			(net "P12V")
			(clearance 0)
		)
		(pad "12" thru_hole circle
			(at 0 27.94 270)
			(size 1.6256 1.6256)
			(drill 1.1176)
			(layers "*.Cu" "*.Mask")
			(remove_unused_layers no)
			(net "P12V")
			(clearance 0)
		)
		(pad "13" thru_hole circle
			(at 0 30.48 270)
			(size 1.6256 1.6256)
			(drill 1.1176)
			(layers "*.Cu" "*.Mask")
			(remove_unused_layers no)
			(net "GND")
			(clearance 0)
		)
		(pad "14" thru_hole circle
			(at 0 33.02 270)
			(size 1.6256 1.6256)
			(drill 1.1176)
			(layers "*.Cu" "*.Mask")
			(remove_unused_layers no)
			(net "GND")
			(clearance 0)
		)
		(pad "15" thru_hole circle
			(at 0 35.56 270)
			(size 1.6256 1.6256)
			(drill 1.1176)
			(layers "*.Cu" "*.Mask")
			(remove_unused_layers no)
			(net "GND")
			(clearance 0)
		)
		(pad "16" thru_hole circle
			(at 0 38.1 270)
			(size 1.6256 1.6256)
			(drill 1.1176)
			(layers "*.Cu" "*.Mask")
			(remove_unused_layers no)
			(net "GND")
			(clearance 0)
		)
		(pad "17" thru_hole circle
			(at 0 40.64 270)
			(size 1.6256 1.6256)
			(drill 1.1176)
			(layers "*.Cu" "*.Mask")
			(remove_unused_layers no)
			(net "GND")
			(clearance 0)
		)
		(pad "18" thru_hole circle
			(at 0 43.18 270)
			(size 1.6256 1.6256)
			(drill 1.1176)
			(layers "*.Cu" "*.Mask")
			(remove_unused_layers no)
			(net "GND")
			(clearance 0)
		)
		(pad "19" thru_hole circle
			(at 0 45.72 270)
			(size 1.6256 1.6256)
			(drill 1.1176)
			(layers "*.Cu" "*.Mask")
			(remove_unused_layers no)
			(net "GND")
			(clearance 0)
		)
		(pad "20" thru_hole circle
			(at 0 48.26 270)
			(size 1.6256 1.6256)
			(drill 1.1176)
			(layers "*.Cu" "*.Mask")
			(remove_unused_layers no)
			(net "GND")
			(clearance 0)
		)
		(pad "21" thru_hole circle
			(at 0 50.8 270)
			(size 1.6256 1.6256)
			(drill 1.1176)
			(layers "*.Cu" "*.Mask")
			(remove_unused_layers no)
			(net "GND")
			(clearance 0)
		)
		(pad "22" thru_hole circle
			(at 0 53.34 270)
			(size 1.6256 1.6256)
			(drill 1.1176)
			(layers "*.Cu" "*.Mask")
			(remove_unused_layers no)
			(net "GND")
			(clearance 0)
		)
		(pad "23" thru_hole circle
			(at 0 55.88 270)
			(size 1.6256 1.6256)
			(drill 1.1176)
			(layers "*.Cu" "*.Mask")
			(remove_unused_layers no)
			(net "GND")
			(clearance 0)
		)
		(pad "24" thru_hole circle
			(at 0 58.42 270)
			(size 1.6256 1.6256)
			(drill 1.1176)
			(layers "*.Cu" "*.Mask")
			(remove_unused_layers no)
			(net "GND")
			(clearance 0)
		)
		(pad "25" thru_hole circle
			(at 0 60.96 270)
			(size 1.6256 1.6256)
			(drill 1.1176)
			(layers "*.Cu" "*.Mask")
			(remove_unused_layers no)
			(net "PHLOSS")
			(clearance 0)
		)
		(pad "26" thru_hole circle
			(at 0 63.5 270)
			(size 1.6256 1.6256)
			(drill 1.1176)
			(layers "*.Cu" "*.Mask")
			(remove_unused_layers no)
			(net "PSU6_REMOTE_N")
			(clearance 0)
		)
		(pad "27" thru_hole circle
			(at 0 66.04 270)
			(size 1.6256 1.6256)
			(drill 1.1176)
			(layers "*.Cu" "*.Mask")
			(remove_unused_layers no)
			(net "PSU6_AC_OK")
			(clearance 0)
		)
		(pad "28" thru_hole circle
			(at 0 68.58 270)
			(size 1.6256 1.6256)
			(drill 1.1176)
			(layers "*.Cu" "*.Mask")
			(remove_unused_layers no)
			(net "PSU6_CSAHRE")
			(clearance 0)
		)
		(pad "29" thru_hole circle
			(at 0 71.12 270)
			(size 1.6256 1.6256)
			(drill 1.1176)
			(layers "*.Cu" "*.Mask")
			(remove_unused_layers no)
			(net "PSU6_PS_ON_N")
			(clearance 0)
		)
		(pad "30" thru_hole circle
			(at 0 73.66 270)
			(size 1.6256 1.6256)
			(drill 1.1176)
			(layers "*.Cu" "*.Mask")
			(remove_unused_layers no)
			(net "PSU6_PS_KILL")
			(clearance 0)
		)
		(pad "31" thru_hole circle
			(at 0 76.2 270)
			(size 1.6256 1.6256)
			(drill 1.1176)
			(layers "*.Cu" "*.Mask")
			(remove_unused_layers no)
			(net "PSU6_RESET")
			(clearance 0)
		)
		(pad "32" thru_hole circle
			(at 0 78.74 270)
			(size 1.6256 1.6256)
			(drill 1.1176)
			(layers "*.Cu" "*.Mask")
			(remove_unused_layers no)
			(net "PSU_ALERT_N")
			(clearance 0)
		)
		(pad "33" thru_hole circle
			(at 5.08 78.74 270)
			(size 1.6256 1.6256)
			(drill 1.1176)
			(layers "*.Cu" "*.Mask")
			(remove_unused_layers no)
			(net "I2C_PSU3_SDA")
			(clearance 0)
		)
		(pad "34" thru_hole circle
			(at 5.08 76.2 270)
			(size 1.6256 1.6256)
			(drill 1.1176)
			(layers "*.Cu" "*.Mask")
			(remove_unused_layers no)
			(net "Net_425")
			(clearance 0)
		)
		(pad "35" thru_hole circle
			(at 5.08 73.66 270)
			(size 1.6256 1.6256)
			(drill 1.1176)
			(layers "*.Cu" "*.Mask")
			(remove_unused_layers no)
			(net "I2C_PSU3_SCL")
			(clearance 0)
		)
		(pad "36" thru_hole circle
			(at 5.08 71.12 270)
			(size 1.6256 1.6256)
			(drill 1.1176)
			(layers "*.Cu" "*.Mask")
			(remove_unused_layers no)
			(net "PSU6_RETURN")
			(clearance 0)
		)
		(pad "37" thru_hole circle
			(at 5.08 68.58 270)
			(size 1.6256 1.6256)
			(drill 1.1176)
			(layers "*.Cu" "*.Mask")
			(remove_unused_layers no)
			(net "PSU6_DC_OK")
			(clearance 0)
		)
		(pad "38" thru_hole circle
			(at 5.08 66.04 270)
			(size 1.6256 1.6256)
			(drill 1.1176)
			(layers "*.Cu" "*.Mask")
			(remove_unused_layers no)
			(net "PSU6_AD0")
			(clearance 0)
		)
		(pad "39" thru_hole circle
			(at 5.08 63.5 270)
			(size 1.6256 1.6256)
			(drill 1.1176)
			(layers "*.Cu" "*.Mask")
			(remove_unused_layers no)
			(net "P12V_STBY")
			(clearance 0)
		)
		(pad "40" thru_hole circle
			(at 5.08 60.96 270)
			(size 1.6256 1.6256)
			(drill 1.1176)
			(layers "*.Cu" "*.Mask")
			(remove_unused_layers no)
			(net "PSU6_REMOTE_P")
			(clearance 0)
		)
		(pad "41" thru_hole circle
			(at 5.08 58.42 270)
			(size 1.6256 1.6256)
			(drill 1.1176)
			(layers "*.Cu" "*.Mask")
			(remove_unused_layers no)
			(net "GND")
			(clearance 0)
		)
		(pad "42" thru_hole circle
			(at 5.08 55.88 270)
			(size 1.6256 1.6256)
			(drill 1.1176)
			(layers "*.Cu" "*.Mask")
			(remove_unused_layers no)
			(net "GND")
			(clearance 0)
		)
		(pad "43" thru_hole circle
			(at 5.08 53.34 270)
			(size 1.6256 1.6256)
			(drill 1.1176)
			(layers "*.Cu" "*.Mask")
			(remove_unused_layers no)
			(net "GND")
			(clearance 0)
		)
		(pad "44" thru_hole circle
			(at 5.08 50.8 270)
			(size 1.6256 1.6256)
			(drill 1.1176)
			(layers "*.Cu" "*.Mask")
			(remove_unused_layers no)
			(net "GND")
			(clearance 0)
		)
		(pad "45" thru_hole circle
			(at 5.08 48.26 270)
			(size 1.6256 1.6256)
			(drill 1.1176)
			(layers "*.Cu" "*.Mask")
			(remove_unused_layers no)
			(net "GND")
			(clearance 0)
		)
		(pad "46" thru_hole circle
			(at 5.08 45.72 270)
			(size 1.6256 1.6256)
			(drill 1.1176)
			(layers "*.Cu" "*.Mask")
			(remove_unused_layers no)
			(net "GND")
			(clearance 0)
		)
		(pad "47" thru_hole circle
			(at 5.08 43.18 270)
			(size 1.6256 1.6256)
			(drill 1.1176)
			(layers "*.Cu" "*.Mask")
			(remove_unused_layers no)
			(net "GND")
			(clearance 0)
		)
		(pad "48" thru_hole circle
			(at 5.08 40.64 270)
			(size 1.6256 1.6256)
			(drill 1.1176)
			(layers "*.Cu" "*.Mask")
			(remove_unused_layers no)
			(net "GND")
			(clearance 0)
		)
		(pad "49" thru_hole circle
			(at 5.08 38.1 270)
			(size 1.6256 1.6256)
			(drill 1.1176)
			(layers "*.Cu" "*.Mask")
			(remove_unused_layers no)
			(net "GND")
			(clearance 0)
		)
		(pad "50" thru_hole circle
			(at 5.08 35.56 270)
			(size 1.6256 1.6256)
			(drill 1.1176)
			(layers "*.Cu" "*.Mask")
			(remove_unused_layers no)
			(net "GND")
			(clearance 0)
		)
		(pad "51" thru_hole circle
			(at 5.08 33.02 270)
			(size 1.6256 1.6256)
			(drill 1.1176)
			(layers "*.Cu" "*.Mask")
			(remove_unused_layers no)
			(net "GND")
			(clearance 0)
		)
		(pad "52" thru_hole circle
			(at 5.08 30.48 270)
			(size 1.6256 1.6256)
			(drill 1.1176)
			(layers "*.Cu" "*.Mask")
			(remove_unused_layers no)
			(net "GND")
			(clearance 0)
		)
		(pad "53" thru_hole circle
			(at 5.08 27.94 270)
			(size 1.6256 1.6256)
			(drill 1.1176)
			(layers "*.Cu" "*.Mask")
			(remove_unused_layers no)
			(net "P12V")
			(clearance 0)
		)
		(pad "54" thru_hole circle
			(at 5.08 25.4 270)
			(size 1.6256 1.6256)
			(drill 1.1176)
			(layers "*.Cu" "*.Mask")
			(remove_unused_layers no)
			(net "P12V")
			(clearance 0)
		)
		(pad "55" thru_hole circle
			(at 5.08 22.86 270)
			(size 1.6256 1.6256)
			(drill 1.1176)
			(layers "*.Cu" "*.Mask")
			(remove_unused_layers no)
			(net "P12V")
			(clearance 0)
		)
		(pad "56" thru_hole circle
			(at 5.08 20.32 270)
			(size 1.6256 1.6256)
			(drill 1.1176)
			(layers "*.Cu" "*.Mask")
			(remove_unused_layers no)
			(net "P12V")
			(clearance 0)
		)
		(pad "57" thru_hole circle
			(at 5.08 17.78 270)
			(size 1.6256 1.6256)
			(drill 1.1176)
			(layers "*.Cu" "*.Mask")
			(remove_unused_layers no)
			(net "P12V")
			(clearance 0)
		)
		(pad "58" thru_hole circle
			(at 5.08 15.24 270)
			(size 1.6256 1.6256)
			(drill 1.1176)
			(layers "*.Cu" "*.Mask")
			(remove_unused_layers no)
			(net "P12V")
			(clearance 0)
		)
		(pad "59" thru_hole circle
			(at 5.08 12.7 270)
			(size 1.6256 1.6256)
			(drill 1.1176)
			(layers "*.Cu" "*.Mask")
			(remove_unused_layers no)
			(net "P12V")
			(clearance 0)
		)
		(pad "60" thru_hole circle
			(at 5.08 10.16 270)
			(size 1.6256 1.6256)
			(drill 1.1176)
			(layers "*.Cu" "*.Mask")
			(remove_unused_layers no)
			(net "P12V")
			(clearance 0)
		)
		(pad "61" thru_hole circle
			(at 5.08 7.62 270)
			(size 1.6256 1.6256)
			(drill 1.1176)
			(layers "*.Cu" "*.Mask")
			(remove_unused_layers no)
			(net "P12V")
			(clearance 0)
		)
		(pad "62" thru_hole circle
			(at 5.08 5.08 270)
			(size 1.6256 1.6256)
			(drill 1.1176)
			(layers "*.Cu" "*.Mask")
			(remove_unused_layers no)
			(net "P12V")
			(clearance 0)
		)
		(pad "63" thru_hole circle
			(at 5.08 2.54 270)
			(size 1.6256 1.6256)
			(drill 1.1176)
			(layers "*.Cu" "*.Mask")
			(remove_unused_layers no)
			(net "P12V")
			(clearance 0)
		)
		(pad "64" thru_hole circle
			(at 5.08 0 270)
			(size 1.6256 1.6256)
			(drill 1.1176)
			(layers "*.Cu" "*.Mask")
			(remove_unused_layers no)
			(net "P12V")
			(clearance 0)
		)
	)
	(footprint ""
		(layer "F.Cu")
		(at 25.857708 -360.550968)
		(property "Reference" "R59"
			(at -3.917442 -0.225298 0)
			(unlocked yes)
			(layer "F.SilkS")
			(effects
				(font
					(size 0.7874 0.5842)
					(thickness 0.1524)
				)
				(justify left)
			)
		)
		(property "Value" ""
			(at 0 0 0)
			(layer "F.Fab")
			(effects
				(font
					(size 1.27 1.27)
				)
			)
		)
		(duplicate_pad_numbers_are_jumpers no)
		(fp_line
			(start -0.7874 -0.4064)
			(end 0.7874 -0.4064)
			(stroke
				(width 0.1524)
				(type default)
			)
			(layer "F.SilkS")
		)
		(fp_line
			(start -0.7874 0.4064)
			(end -0.7874 -0.4064)
			(stroke
				(width 0.1524)
				(type default)
			)
			(layer "F.SilkS")
		)
		(fp_line
			(start 0.7874 -0.4064)
			(end 0.7874 0.4064)
			(stroke
				(width 0.1524)
				(type default)
			)
			(layer "F.SilkS")
		)
		(fp_line
			(start 0.7874 0.4064)
			(end -0.7874 0.4064)
			(stroke
				(width 0.1524)
				(type default)
			)
			(layer "F.SilkS")
		)
		(fp_poly
			(pts
				(xy -0.508 0.2794) (xy -0.508 0.2286) (xy -0.635 0.2286) (xy -0.635 -0.254) (xy -0.5334 -0.254)
				(xy -0.5334 -0.2794) (xy 0.5334 -0.2794) (xy 0.5334 -0.254) (xy 0.635 -0.254) (xy 0.635 0.254) (xy 0.5334 0.254)
				(xy 0.5334 0.2794)
			)
			(stroke
				(width 0)
				(type default)
			)
			(fill no)
			(layer "F.CrtYd")
		)
		(pad "1" smd rect
			(at 0.40005 0)
			(size 0.4572 0.508)
			(layers "F.Cu" "F.Mask" "F.Paste")
			(net "PSU5_RESET")
		)
		(pad "2" smd rect
			(at -0.40005 0)
			(size 0.4572 0.508)
			(layers "F.Cu" "F.Mask" "F.Paste")
			(net "GND")
		)
	)
)
